(kicad_pcb
	(version 20241229)
	(generator "pcbnew")
	(generator_version "9.0")
	(general
		(thickness 1.62)
		(legacy_teardrops no)
	)
	(paper "A3")
	(title_block
		(title "COM Express 7 Baseboard")
		(date "2025-02-04")
		(rev "1.1.2")
		(company "Antmicro Ltd")
		(comment 1 "www.antmicro.com")
		(comment 9 "footprints 88-92 of 802")
	)
	(layers
		(0 "F.Cu" signal)
		(4 "In1.Cu" signal)
		(6 "In2.Cu" signal)
		(8 "In3.Cu" signal)
		(10 "In4.Cu" signal)
		(12 "In5.Cu" signal)
		(14 "In6.Cu" signal)
		(2 "B.Cu" signal)
		(9 "F.Adhes" user "F.Adhesive")
		(11 "B.Adhes" user "B.Adhesive")
		(13 "F.Paste" user)
		(15 "B.Paste" user)
		(5 "F.SilkS" user "F.Silkscreen")
		(7 "B.SilkS" user "B.Silkscreen")
		(1 "F.Mask" user)
		(3 "B.Mask" user)
		(17 "Dwgs.User" user "User.Drawings")
		(19 "Cmts.User" user "User.Comments")
		(21 "Eco1.User" user "User.Eco1")
		(23 "Eco2.User" user "User.Eco2")
		(25 "Edge.Cuts" user)
		(27 "Margin" user)
		(31 "F.CrtYd" user "F.Courtyard")
		(29 "B.CrtYd" user "B.Courtyard")
		(35 "F.Fab" user)
		(33 "B.Fab" user)
	)
	(footprint "antmicro-footprints:R_0402_1005Metric"
		(layer "F.Cu")
		(at 289.85 101.86)
		(descr "Resistor SMD 0402")
		(tags "resistor SMD 0402")
		(property "Reference" "R117"
			(at -1.45 2.35 0)
			(layer "F.SilkS")
			(effects
				(font
					(size 0.7 0.7)
					(thickness 0.15)
				)
				(justify left bottom)
			)
		)
		(property "Value" "R_30k_0402"
			(at -1.011843 1.772047 0)
			(layer "F.Fab")
			(effects
				(font
					(size 0.7 0.7)
					(thickness 0.15)
				)
				(justify left bottom)
			)
		)
		(property "Datasheet" "https://www.bourns.com/docs/product-datasheets/cr.pdf"
			(at 0 0 0)
			(layer "F.Fab")
			(hide yes)
			(effects
				(font
					(size 1.27 1.27)
					(thickness 0.15)
				)
			)
		)
		(property "Author" "Antmicro"
			(at 0 0 0)
			(layer "F.Fab")
			(hide yes)
			(effects
				(font
					(size 1 1)
					(thickness 0.15)
				)
			)
		)
		(property "License" "Apache-2.0"
			(at 0 0 0)
			(layer "F.Fab")
			(hide yes)
			(effects
				(font
					(size 1 1)
					(thickness 0.15)
				)
			)
		)
		(property "MPN" "CR0402-FX-3002GLF"
			(at 0 0 0)
			(layer "F.Fab")
			(hide yes)
			(effects
				(font
					(size 1 1)
					(thickness 0.15)
				)
			)
		)
		(property "Manufacturer" "Bourns"
			(at 0 0 0)
			(layer "F.Fab")
			(hide yes)
			(effects
				(font
					(size 1 1)
					(thickness 0.15)
				)
			)
		)
		(property "Public" "False"
			(at 0 0 0)
			(layer "F.Fab")
			(hide yes)
			(effects
				(font
					(size 1 1)
					(thickness 0.15)
				)
			)
		)
		(property "Tolerance" "1%"
			(at 0 0 0)
			(layer "F.Fab")
			(hide yes)
			(effects
				(font
					(size 1 1)
					(thickness 0.15)
				)
			)
		)
		(property "Val" "30k"
			(at 0 0 0)
			(layer "F.Fab")
			(hide yes)
			(effects
				(font
					(size 1 1)
					(thickness 0.15)
				)
			)
		)
		(sheetname "Power")
		(sheetfile "power.kicad_sch")
		(attr smd)
		(fp_rect
			(start -0.925 -0.47)
			(end 0.925 0.47)
			(stroke
				(width 0.05)
				(type default)
			)
			(fill no)
			(layer "F.CrtYd")
		)
		(fp_rect
			(start -0.5 -0.25)
			(end 0.5 0.25)
			(stroke
				(width 0.15)
				(type solid)
			)
			(fill no)
			(layer "F.Fab")
		)
		(pad "1" smd roundrect
			(at -0.48 0)
			(size 0.59 0.64)
			(layers "F.Cu" "F.Mask" "F.Paste")
			(roundrect_rratio 0.25)
			(net 535 "Net-(Q3-G)")
			(pintype "passive")
			(teardrops
				(best_length_ratio 0.2)
				(max_length 1)
				(best_width_ratio 0.9)
				(max_width 2)
				(curved_edges yes)
				(filter_ratio 0.9)
				(enabled yes)
				(allow_two_segments yes)
				(prefer_zone_connections yes)
			)
		)
		(pad "2" smd roundrect
			(at 0.48 0)
			(size 0.59 0.64)
			(layers "F.Cu" "F.Mask" "F.Paste")
			(roundrect_rratio 0.25)
			(net 1 "GND")
			(pintype "passive")
			(teardrops
				(best_length_ratio 0.2)
				(max_length 1)
				(best_width_ratio 0.9)
				(max_width 2)
				(curved_edges yes)
				(filter_ratio 0.9)
				(enabled yes)
				(allow_two_segments yes)
				(prefer_zone_connections yes)
			)
		)
	)
	(footprint "antmicro-footprints:SOT-23-3"
		(layer "F.Cu")
		(at 250.9 127.16 180)
		(property "Reference" "Q11"
			(at 0.95 2.65 90)
			(layer "F.SilkS")
			(effects
				(font
					(size 0.7 0.7)
					(thickness 0.15)
				)
				(justify right bottom)
			)
		)
		(property "Value" "BSS138-7-F"
			(at -1.9 2.7 0)
			(layer "F.Fab")
			(effects
				(font
					(size 0.7 0.7)
					(thickness 0.15)
				)
				(justify right bottom)
			)
		)
		(property "Datasheet" "https://www.diodes.com/assets/Datasheets/ds30144.pdf"
			(at 0 0 180)
			(layer "F.Fab")
			(hide yes)
			(effects
				(font
					(size 1.27 1.27)
					(thickness 0.15)
				)
			)
		)
		(property "Author" "Antmicro"
			(at 501.8 254.32 0)
			(layer "F.Fab")
			(hide yes)
			(effects
				(font
					(size 1 1)
					(thickness 0.15)
				)
			)
		)
		(property "License" "Apache-2.0"
			(at 501.8 254.32 0)
			(layer "F.Fab")
			(hide yes)
			(effects
				(font
					(size 1 1)
					(thickness 0.15)
				)
			)
		)
		(property "MPN" "BSS138-7-F"
			(at 501.8 254.32 0)
			(layer "F.Fab")
			(hide yes)
			(effects
				(font
					(size 1 1)
					(thickness 0.15)
				)
			)
		)
		(property "Manufacturer" "Diodes Incorporated"
			(at 501.8 254.32 0)
			(layer "F.Fab")
			(hide yes)
			(effects
				(font
					(size 1 1)
					(thickness 0.15)
				)
			)
		)
		(sheetname "Com Express 7 MGMT")
		(sheetfile "com_express_7_mgmt.kicad_sch")
		(attr smd)
		(fp_line
			(start 0.7 1.5)
			(end -0.7 1.5)
			(stroke
				(width 0.15)
				(type solid)
			)
			(layer "F.SilkS")
		)
		(fp_line
			(start 0.7 0.4)
			(end 0.7 1.5)
			(stroke
				(width 0.15)
				(type solid)
			)
			(layer "F.SilkS")
		)
		(fp_line
			(start 0.7 -0.4)
			(end 0.7 -1.5)
			(stroke
				(width 0.15)
				(type solid)
			)
			(layer "F.SilkS")
		)
		(fp_line
			(start 0.7 -1.5)
			(end -0.7 -1.5)
			(stroke
				(width 0.15)
				(type solid)
			)
			(layer "F.SilkS")
		)
		(fp_line
			(start -0.7 1.5)
			(end -0.7 1.35)
			(stroke
				(width 0.15)
				(type solid)
			)
			(layer "F.SilkS")
		)
		(fp_line
			(start -0.85 -1.35)
			(end -0.7 -1.5)
			(stroke
				(width 0.15)
				(type solid)
			)
			(layer "F.SilkS")
		)
		(fp_line
			(start -1.45 -1.35)
			(end -0.85 -1.35)
			(stroke
				(width 0.15)
				(type solid)
			)
			(layer "F.SilkS")
		)
		(fp_line
			(start 1.75 0.45)
			(end 0.85 0.45)
			(stroke
				(width 0.05)
				(type solid)
			)
			(layer "F.CrtYd")
		)
		(fp_line
			(start 1.75 -0.45)
			(end 1.75 0.45)
			(stroke
				(width 0.05)
				(type solid)
			)
			(layer "F.CrtYd")
		)
		(fp_line
			(start 0.85 1.65)
			(end -0.85 1.65)
			(stroke
				(width 0.05)
				(type solid)
			)
			(layer "F.CrtYd")
		)
		(fp_line
			(start 0.85 0.45)
			(end 0.85 1.65)
			(stroke
				(width 0.05)
				(type solid)
			)
			(layer "F.CrtYd")
		)
		(fp_line
			(start 0.825 -0.45)
			(end 1.75 -0.45)
			(stroke
				(width 0.05)
				(type solid)
			)
			(layer "F.CrtYd")
		)
		(fp_line
			(start 0.825 -1.6)
			(end 0.825 -0.45)
			(stroke
				(width 0.05)
				(type solid)
			)
			(layer "F.CrtYd")
		)
		(fp_line
			(start -0.85 1.65)
			(end -0.85 1.4)
			(stroke
				(width 0.05)
				(type solid)
			)
			(layer "F.CrtYd")
		)
		(fp_line
			(start -0.85 1.4)
			(end -1.75 1.4)
			(stroke
				(width 0.05)
				(type solid)
			)
			(layer "F.CrtYd")
		)
		(fp_line
			(start -0.85 0.5)
			(end -0.85 -0.5)
			(stroke
				(width 0.05)
				(type solid)
			)
			(layer "F.CrtYd")
		)
		(fp_line
			(start -0.85 -0.5)
			(end -1.75 -0.5)
			(stroke
				(width 0.05)
				(type solid)
			)
			(layer "F.CrtYd")
		)
		(fp_line
			(start -0.9 -1.4)
			(end -1.75 -1.4)
			(stroke
				(width 0.05)
				(type solid)
			)
			(layer "F.CrtYd")
		)
		(fp_line
			(start -0.9 -1.6)
			(end 0.825 -1.6)
			(stroke
				(width 0.05)
				(type solid)
			)
			(layer "F.CrtYd")
		)
		(fp_line
			(start -0.9 -1.6)
			(end -0.9 -1.4)
			(stroke
				(width 0.05)
				(type solid)
			)
			(layer "F.CrtYd")
		)
		(fp_line
			(start -1.75 1.4)
			(end -1.75 0.5)
			(stroke
				(width 0.05)
				(type solid)
			)
			(layer "F.CrtYd")
		)
		(fp_line
			(start -1.75 0.5)
			(end -0.85 0.5)
			(stroke
				(width 0.05)
				(type solid)
			)
			(layer "F.CrtYd")
		)
		(fp_line
			(start -1.75 -0.5)
			(end -1.75 -1.4)
			(stroke
				(width 0.05)
				(type solid)
			)
			(layer "F.CrtYd")
		)
		(fp_line
			(start 0.688 1.519)
			(end 0.688 -1.52)
			(stroke
				(width 0.15)
				(type solid)
			)
			(layer "F.Fab")
		)
		(fp_line
			(start -0.437 -1.526)
			(end 0.688 -1.526)
			(stroke
				(width 0.15)
				(type solid)
			)
			(layer "F.Fab")
		)
		(fp_line
			(start -0.437 -1.526)
			(end -0.712 -1.325)
			(stroke
				(width 0.15)
				(type solid)
			)
			(layer "F.Fab")
		)
		(fp_line
			(start -0.712 1.519)
			(end 0.688 1.519)
			(stroke
				(width 0.15)
				(type solid)
			)
			(layer "F.Fab")
		)
		(fp_line
			(start -0.712 -1.325)
			(end -0.712 1.523)
			(stroke
				(width 0.15)
				(type solid)
			)
			(layer "F.Fab")
		)
		(pad "1" smd roundrect
			(at -1.1 -0.951 180)
			(size 1 0.6)
			(layers "F.Cu" "F.Mask" "F.Paste")
			(roundrect_rratio 0.15)
			(net 545 "Net-(Q11-G)")
			(pinfunction "G")
			(pintype "bidirectional")
			(teardrops
				(best_length_ratio 0.2)
				(max_length 1)
				(best_width_ratio 0.9)
				(max_width 2)
				(curved_edges yes)
				(filter_ratio 0.9)
				(enabled yes)
				(allow_two_segments yes)
				(prefer_zone_connections yes)
			)
		)
		(pad "2" smd roundrect
			(at -1.1 0.949 180)
			(size 1 0.6)
			(layers "F.Cu" "F.Mask" "F.Paste")
			(roundrect_rratio 0.15)
			(net 1 "GND")
			(pinfunction "S")
			(pintype "bidirectional")
			(teardrops
				(best_length_ratio 0.2)
				(max_length 1)
				(best_width_ratio 0.9)
				(max_width 2)
				(curved_edges yes)
				(filter_ratio 0.9)
				(enabled yes)
				(allow_two_segments yes)
				(prefer_zone_connections yes)
			)
		)
		(pad "3" smd roundrect
			(at 1.1 -0.0005 180)
			(size 1 0.6)
			(layers "F.Cu" "F.Mask" "F.Paste")
			(roundrect_rratio 0.15)
			(net 83 "Net-(Q11-D)")
			(pinfunction "D")
			(pintype "bidirectional")
			(teardrops
				(best_length_ratio 0.2)
				(max_length 1)
				(best_width_ratio 0.9)
				(max_width 2)
				(curved_edges yes)
				(filter_ratio 0.9)
				(enabled yes)
				(allow_two_segments yes)
				(prefer_zone_connections yes)
			)
		)
	)
	(footprint "antmicro-footprints:TP_SMD_0.75mm"
		(layer "F.Cu")
		(at 131.69 129.56)
		(property "Reference" "TP91"
			(at 0.46 -1.25 90)
			(layer "F.SilkS")
			(effects
				(font
					(size 0.7 0.7)
					(thickness 0.15)
				)
				(justify left bottom)
			)
		)
		(property "Value" "TP_0.75mm_SMD"
			(at 0 1.2 0)
			(layer "F.Fab")
			(effects
				(font
					(size 0.7 0.7)
					(thickness 0.15)
				)
				(justify left bottom)
			)
		)
		(property "Author" "Antmicro"
			(at 0 0 0)
			(layer "F.Fab")
			(hide yes)
			(effects
				(font
					(size 1 1)
					(thickness 0.15)
				)
			)
		)
		(property "License" "Apache-2.0"
			(at 0 0 0)
			(layer "F.Fab")
			(hide yes)
			(effects
				(font
					(size 1 1)
					(thickness 0.15)
				)
			)
		)
		(property "MPN" ""
			(at 0 0 0)
			(layer "F.Fab")
			(hide yes)
			(effects
				(font
					(size 1 1)
					(thickness 0.15)
				)
			)
		)
		(property "Manufacturer" ""
			(at 0 0 0)
			(layer "F.Fab")
			(hide yes)
			(effects
				(font
					(size 1 1)
					(thickness 0.15)
				)
			)
		)
		(property "Public" "False"
			(at 0 0 0)
			(layer "F.Fab")
			(hide yes)
			(effects
				(font
					(size 1 1)
					(thickness 0.15)
				)
			)
		)
		(sheetname "KR to SFI #2")
		(sheetfile "kr_sfi.kicad_sch")
		(attr exclude_from_pos_files exclude_from_bom)
		(fp_circle
			(center 0 0)
			(end 0.475 0)
			(stroke
				(width 0.05)
				(type default)
			)
			(fill no)
			(layer "F.CrtYd")
		)
		(pad "1" smd circle
			(at 0 0)
			(size 0.75 0.75)
			(layers "F.Cu" "F.Mask")
			(net 754 "Net-(U45A-LOSA)")
			(pinfunction "1")
			(pintype "passive")
			(teardrops
				(best_length_ratio 0.4)
				(max_length 1)
				(best_width_ratio 0.9)
				(max_width 2)
				(curved_edges yes)
				(filter_ratio 0.9)
				(enabled yes)
				(allow_two_segments yes)
				(prefer_zone_connections yes)
			)
		)
	)
	(footprint "antmicro-footprints:R_0402_1005Metric"
		(layer "F.Cu")
		(at 122.05 92.96 180)
		(descr "Resistor SMD 0402")
		(tags "resistor SMD 0402")
		(property "Reference" "R28"
			(at -2.95 -0.4 0)
			(layer "F.SilkS")
			(effects
				(font
					(size 0.7 0.7)
					(thickness 0.15)
				)
				(justify right bottom)
			)
		)
		(property "Value" "R_0R_0402"
			(at -1.011843 1.772047 0)
			(layer "F.Fab")
			(effects
				(font
					(size 0.7 0.7)
					(thickness 0.15)
				)
				(justify right bottom)
			)
		)
		(property "Datasheet" "https://industrial.panasonic.com/cdbs/www-data/pdf/RDA0000/AOA0000C301.pdf"
			(at 0 0 180)
			(layer "F.Fab")
			(hide yes)
			(effects
				(font
					(size 1.27 1.27)
					(thickness 0.15)
				)
			)
		)
		(property "Author" "Antmicro"
			(at 244.1 185.92 0)
			(layer "F.Fab")
			(hide yes)
			(effects
				(font
					(size 1 1)
					(thickness 0.15)
				)
			)
		)
		(property "Current" "1A"
			(at 244.1 185.92 0)
			(layer "F.Fab")
			(hide yes)
			(effects
				(font
					(size 1 1)
					(thickness 0.15)
				)
			)
		)
		(property "License" "Apache-2.0"
			(at 244.1 185.92 0)
			(layer "F.Fab")
			(hide yes)
			(effects
				(font
					(size 1 1)
					(thickness 0.15)
				)
			)
		)
		(property "MPN" "ERJ2GE0R00X"
			(at 244.1 185.92 0)
			(layer "F.Fab")
			(hide yes)
			(effects
				(font
					(size 1 1)
					(thickness 0.15)
				)
			)
		)
		(property "Manufacturer" "Panasonic"
			(at 244.1 185.92 0)
			(layer "F.Fab")
			(hide yes)
			(effects
				(font
					(size 1 1)
					(thickness 0.15)
				)
			)
		)
		(property "Public" "False"
			(at 244.1 185.92 0)
			(layer "F.Fab")
			(hide yes)
			(effects
				(font
					(size 1 1)
					(thickness 0.15)
				)
			)
		)
		(property "Tolerance" ""
			(at 244.1 185.92 0)
			(layer "F.Fab")
			(hide yes)
			(effects
				(font
					(size 1 1)
					(thickness 0.15)
				)
			)
		)
		(property "Val" "0R"
			(at 244.1 185.92 0)
			(layer "F.Fab")
			(hide yes)
			(effects
				(font
					(size 1 1)
					(thickness 0.15)
				)
			)
		)
		(sheetname "2xUSB3.0+RJ45")
		(sheetfile "usb3+rj45.kicad_sch")
		(attr smd)
		(fp_rect
			(start -0.925 -0.47)
			(end 0.925 0.47)
			(stroke
				(width 0.05)
				(type default)
			)
			(fill no)
			(layer "F.CrtYd")
		)
		(fp_rect
			(start -0.5 -0.25)
			(end 0.5 0.25)
			(stroke
				(width 0.15)
				(type solid)
			)
			(fill no)
			(layer "F.Fab")
		)
		(pad "1" smd roundrect
			(at -0.48 0 180)
			(size 0.59 0.64)
			(layers "F.Cu" "F.Mask" "F.Paste")
			(roundrect_rratio 0.25)
			(net 314 "/2xUSB3.0+RJ45/FLG_1")
			(pintype "passive")
			(teardrops
				(best_length_ratio 0.2)
				(max_length 1)
				(best_width_ratio 0.9)
				(max_width 2)
				(curved_edges yes)
				(filter_ratio 0.9)
				(enabled yes)
				(allow_two_segments yes)
				(prefer_zone_connections yes)
			)
		)
		(pad "2" smd roundrect
			(at 0.48 0 180)
			(size 0.59 0.64)
			(layers "F.Cu" "F.Mask" "F.Paste")
			(roundrect_rratio 0.25)
			(net 554 "/2xUSB3.0+RJ45/FLG_2B")
			(pintype "passive")
			(teardrops
				(best_length_ratio 0.2)
				(max_length 1)
				(best_width_ratio 0.9)
				(max_width 2)
				(curved_edges yes)
				(filter_ratio 0.9)
				(enabled yes)
				(allow_two_segments yes)
				(prefer_zone_connections yes)
			)
		)
	)
	(footprint "antmicro-footprints:R_0402_1005Metric"
		(layer "F.Cu")
		(at 155.299 165.36 180)
		(descr "Resistor SMD 0402")
		(tags "resistor SMD 0402")
		(property "Reference" "R63"
			(at -4.551 18.05 0)
			(layer "F.SilkS")
			(effects
				(font
					(size 0.7 0.7)
					(thickness 0.15)
				)
				(justify left bottom)
			)
		)
		(property "Value" "R_220R_0402"
			(at -1.011843 1.772047 0)
			(layer "F.Fab")
			(effects
				(font
					(size 0.7 0.7)
					(thickness 0.15)
				)
				(justify right bottom)
			)
		)
		(property "Datasheet" "https://www.bourns.com/docs/product-datasheets/cr.pdf"
			(at 0 0 180)
			(layer "F.Fab")
			(hide yes)
			(effects
				(font
					(size 1.27 1.27)
					(thickness 0.15)
				)
			)
		)
		(property "Author" "Antmicro"
			(at 310.598 330.72 0)
			(layer "F.Fab")
			(hide yes)
			(effects
				(font
					(size 1 1)
					(thickness 0.15)
				)
			)
		)
		(property "License" "Apache-2.0"
			(at 310.598 330.72 0)
			(layer "F.Fab")
			(hide yes)
			(effects
				(font
					(size 1 1)
					(thickness 0.15)
				)
			)
		)
		(property "MPN" "CR0402-FX-2200GLF"
			(at 310.598 330.72 0)
			(layer "F.Fab")
			(hide yes)
			(effects
				(font
					(size 1 1)
					(thickness 0.15)
				)
			)
		)
		(property "Manufacturer" "Bourns"
			(at 310.598 330.72 0)
			(layer "F.Fab")
			(hide yes)
			(effects
				(font
					(size 1 1)
					(thickness 0.15)
				)
			)
		)
		(property "Public" "False"
			(at 310.598 330.72 0)
			(layer "F.Fab")
			(hide yes)
			(effects
				(font
					(size 1 1)
					(thickness 0.15)
				)
			)
		)
		(property "Tolerance" "1%"
			(at 310.598 330.72 0)
			(layer "F.Fab")
			(hide yes)
			(effects
				(font
					(size 1 1)
					(thickness 0.15)
				)
			)
		)
		(property "Val" "220R"
			(at 310.598 330.72 0)
			(layer "F.Fab")
			(hide yes)
			(effects
				(font
					(size 1 1)
					(thickness 0.15)
				)
			)
		)
		(sheetname "2xSFP+")
		(sheetfile "2xSFP+.kicad_sch")
		(attr smd)
		(fp_rect
			(start -0.925 -0.47)
			(end 0.925 0.47)
			(stroke
				(width 0.05)
				(type default)
			)
			(fill no)
			(layer "F.CrtYd")
		)
		(fp_rect
			(start -0.5 -0.25)
			(end 0.5 0.25)
			(stroke
				(width 0.15)
				(type solid)
			)
			(fill no)
			(layer "F.Fab")
		)
		(pad "1" smd roundrect
			(at -0.48 0 180)
			(size 0.59 0.64)
			(layers "F.Cu" "F.Mask" "F.Paste")
			(roundrect_rratio 0.25)
			(net 939 "/2xSFP+/SFP0_LEDY")
			(pintype "passive")
			(teardrops
				(best_length_ratio 0.2)
				(max_length 1)
				(best_width_ratio 0.9)
				(max_width 2)
				(curved_edges yes)
				(filter_ratio 0.9)
				(enabled yes)
				(allow_two_segments yes)
				(prefer_zone_connections yes)
			)
		)
		(pad "2" smd roundrect
			(at 0.48 0 180)
			(size 0.59 0.64)
			(layers "F.Cu" "F.Mask" "F.Paste")
			(roundrect_rratio 0.25)
			(net 899 "Net-(D4-C)")
			(pintype "passive")
			(teardrops
				(best_length_ratio 0.2)
				(max_length 1)
				(best_width_ratio 0.9)
				(max_width 2)
				(curved_edges yes)
				(filter_ratio 0.9)
				(enabled yes)
				(allow_two_segments yes)
				(prefer_zone_connections yes)
			)
		)
	)
)
